(kicad_pcb
	(version 20260206)
	(generator "pcbnew")
	(generator_version "10.0")
	(general
		(thickness 1.6)
		(legacy_teardrops no)
	)
	(paper "A4")
	(title_block
		(title "v1-pdb — T6M_PDB_D_0927_0900.brd")
		(comment 1 "Open CloudServer (Microsoft) / footprints 114-124 of 321")
	)
	(layers
		(0 "F.Cu" signal "TOP")
		(4 "In1.Cu" signal "GND")
		(6 "In2.Cu" signal "IN1")
		(8 "In3.Cu" signal "VCC")
		(10 "In4.Cu" signal "VCC1")
		(12 "In5.Cu" signal "IN2")
		(14 "In6.Cu" signal "GND1")
		(2 "B.Cu" signal "BOTTOM")
		(9 "F.Adhes" user "F.Adhesive")
		(11 "B.Adhes" user "B.Adhesive")
		(13 "F.Paste" user "Package Geometry/Pastemask Top")
		(15 "B.Paste" user "Package Geometry/Pastemask Bottom")
		(5 "F.SilkS" user "Ref Des/Silkscreen Top")
		(7 "B.SilkS" user "Ref Des/Silkscreen Bottom")
		(1 "F.Mask" user "Board Geometry/Soldermask Top")
		(3 "B.Mask" user "Board Geometry/Soldermask Bottom")
		(17 "Dwgs.User" user "User.Drawings")
		(19 "Cmts.User" user "User.Comments")
		(21 "Eco1.User" user "User.Eco1")
		(23 "Eco2.User" user "User.Eco2")
		(25 "Edge.Cuts" user "Board Geometry/Outline")
		(27 "Margin" user)
		(31 "F.CrtYd" user "Package Geometry/Place Bound Top")
		(29 "B.CrtYd" user "Package Geometry/Place Bound Bottom")
		(35 "F.Fab" user "Ref Des/Assembly Top")
		(33 "B.Fab" user "Ref Des/Assembly Bottom")
	)
	(footprint ""
		(layer "F.Cu")
		(at 27.347672 -108.630466 -90)
		(property "Reference" "R93"
			(at -0.391414 1.160526 90)
			(unlocked yes)
			(layer "F.SilkS")
			(effects
				(font
					(size 0.7874 0.5842)
					(thickness 0.1524)
				)
				(justify left)
			)
		)
		(property "Value" ""
			(at 0 0 270)
			(layer "F.Fab")
			(effects
				(font
					(size 1.27 1.27)
				)
			)
		)
		(duplicate_pad_numbers_are_jumpers no)
		(fp_line
			(start -0.7874 0.4064)
			(end -0.7874 -0.4064)
			(stroke
				(width 0.1524)
				(type default)
			)
			(layer "F.SilkS")
		)
		(fp_line
			(start 0.7874 0.4064)
			(end -0.7874 0.4064)
			(stroke
				(width 0.1524)
				(type default)
			)
			(layer "F.SilkS")
		)
		(fp_line
			(start -0.7874 -0.4064)
			(end 0.7874 -0.4064)
			(stroke
				(width 0.1524)
				(type default)
			)
			(layer "F.SilkS")
		)
		(fp_line
			(start 0.7874 -0.4064)
			(end 0.7874 0.4064)
			(stroke
				(width 0.1524)
				(type default)
			)
			(layer "F.SilkS")
		)
		(fp_poly
			(pts
				(xy -0.508 0.2794) (xy -0.508 0.2286) (xy -0.635 0.2286) (xy -0.635 -0.254) (xy -0.5334 -0.254)
				(xy -0.5334 -0.2794) (xy 0.5334 -0.2794) (xy 0.5334 -0.254) (xy 0.635 -0.254) (xy 0.635 0.254) (xy 0.5334 0.254)
				(xy 0.5334 0.2794)
			)
			(stroke
				(width 0)
				(type default)
			)
			(fill no)
			(layer "F.CrtYd")
		)
		(pad "1" smd rect
			(at 0.40005 0 270)
			(size 0.4572 0.508)
			(layers "F.Cu" "F.Mask" "F.Paste")
			(net "PSU2_REMOTE_N")
		)
		(pad "2" smd rect
			(at -0.40005 0 270)
			(size 0.4572 0.508)
			(layers "F.Cu" "F.Mask" "F.Paste")
			(net "PSU2_REMOTE_R_N")
		)
	)
	(footprint ""
		(layer "F.Cu")
		(at 25.997662 -7.19328)
		(property "Reference" "R62"
			(at -3.764788 0.113792 0)
			(unlocked yes)
			(layer "F.SilkS")
			(effects
				(font
					(size 0.7874 0.5842)
					(thickness 0.1524)
				)
				(justify left)
			)
		)
		(property "Value" ""
			(at 0 0 0)
			(layer "F.Fab")
			(effects
				(font
					(size 1.27 1.27)
				)
			)
		)
		(duplicate_pad_numbers_are_jumpers no)
		(fp_line
			(start -0.7874 -0.4064)
			(end 0.7874 -0.4064)
			(stroke
				(width 0.1524)
				(type default)
			)
			(layer "F.SilkS")
		)
		(fp_line
			(start -0.7874 0.4064)
			(end -0.7874 -0.4064)
			(stroke
				(width 0.1524)
				(type default)
			)
			(layer "F.SilkS")
		)
		(fp_line
			(start 0.7874 -0.4064)
			(end 0.7874 0.4064)
			(stroke
				(width 0.1524)
				(type default)
			)
			(layer "F.SilkS")
		)
		(fp_line
			(start 0.7874 0.4064)
			(end -0.7874 0.4064)
			(stroke
				(width 0.1524)
				(type default)
			)
			(layer "F.SilkS")
		)
		(fp_poly
			(pts
				(xy -0.508 0.2794) (xy -0.508 0.2286) (xy -0.635 0.2286) (xy -0.635 -0.254) (xy -0.5334 -0.254)
				(xy -0.5334 -0.2794) (xy 0.5334 -0.2794) (xy 0.5334 -0.254) (xy 0.635 -0.254) (xy 0.635 0.254) (xy 0.5334 0.254)
				(xy 0.5334 0.2794)
			)
			(stroke
				(width 0)
				(type default)
			)
			(fill no)
			(layer "F.CrtYd")
		)
		(pad "1" smd rect
			(at 0.40005 0)
			(size 0.4572 0.508)
			(layers "F.Cu" "F.Mask" "F.Paste")
			(net "PSU1_PS_KILL")
		)
		(pad "2" smd rect
			(at -0.40005 0)
			(size 0.4572 0.508)
			(layers "F.Cu" "F.Mask" "F.Paste")
			(net "P12V_STBY")
		)
	)
	(footprint ""
		(layer "F.Cu")
		(at 27.334718 -196.234304 90)
		(property "Reference" "R121"
			(at -3.838194 0.013462 90)
			(unlocked yes)
			(layer "F.SilkS")
			(effects
				(font
					(size 0.7874 0.5842)
					(thickness 0.1524)
				)
				(justify left)
			)
		)
		(property "Value" ""
			(at 0 0 90)
			(layer "F.Fab")
			(effects
				(font
					(size 1.27 1.27)
				)
			)
		)
		(duplicate_pad_numbers_are_jumpers no)
		(fp_line
			(start 0.7874 -0.4064)
			(end 0.7874 0.4064)
			(stroke
				(width 0.1524)
				(type default)
			)
			(layer "F.SilkS")
		)
		(fp_line
			(start -0.7874 -0.4064)
			(end 0.7874 -0.4064)
			(stroke
				(width 0.1524)
				(type default)
			)
			(layer "F.SilkS")
		)
		(fp_line
			(start 0.7874 0.4064)
			(end -0.7874 0.4064)
			(stroke
				(width 0.1524)
				(type default)
			)
			(layer "F.SilkS")
		)
		(fp_line
			(start -0.7874 0.4064)
			(end -0.7874 -0.4064)
			(stroke
				(width 0.1524)
				(type default)
			)
			(layer "F.SilkS")
		)
		(fp_poly
			(pts
				(xy -0.508 0.2794) (xy -0.508 0.2286) (xy -0.635 0.2286) (xy -0.635 -0.254) (xy -0.5334 -0.254)
				(xy -0.5334 -0.2794) (xy 0.5334 -0.2794) (xy 0.5334 -0.254) (xy 0.635 -0.254) (xy 0.635 0.254) (xy 0.5334 0.254)
				(xy 0.5334 0.2794)
			)
			(stroke
				(width 0)
				(type default)
			)
			(fill no)
			(layer "F.CrtYd")
		)
		(pad "1" smd rect
			(at 0.40005 0 90)
			(size 0.4572 0.508)
			(layers "F.Cu" "F.Mask" "F.Paste")
			(net "PSU3_REMOTE_N")
		)
		(pad "2" smd rect
			(at -0.40005 0 90)
			(size 0.4572 0.508)
			(layers "F.Cu" "F.Mask" "F.Paste")
			(net "PSU3_REMOTE_R2_N")
		)
	)
	(footprint ""
		(layer "F.Cu")
		(at 25.857708 -366.710722)
		(property "Reference" "R58"
			(at -3.917442 -0.225298 0)
			(unlocked yes)
			(layer "F.SilkS")
			(effects
				(font
					(size 0.7874 0.5842)
					(thickness 0.1524)
				)
				(justify left)
			)
		)
		(property "Value" ""
			(at 0 0 0)
			(layer "F.Fab")
			(effects
				(font
					(size 1.27 1.27)
				)
			)
		)
		(duplicate_pad_numbers_are_jumpers no)
		(fp_line
			(start -0.7874 -0.4064)
			(end 0.7874 -0.4064)
			(stroke
				(width 0.1524)
				(type default)
			)
			(layer "F.SilkS")
		)
		(fp_line
			(start -0.7874 0.4064)
			(end -0.7874 -0.4064)
			(stroke
				(width 0.1524)
				(type default)
			)
			(layer "F.SilkS")
		)
		(fp_line
			(start 0.7874 -0.4064)
			(end 0.7874 0.4064)
			(stroke
				(width 0.1524)
				(type default)
			)
			(layer "F.SilkS")
		)
		(fp_line
			(start 0.7874 0.4064)
			(end -0.7874 0.4064)
			(stroke
				(width 0.1524)
				(type default)
			)
			(layer "F.SilkS")
		)
		(fp_poly
			(pts
				(xy -0.508 0.2794) (xy -0.508 0.2286) (xy -0.635 0.2286) (xy -0.635 -0.254) (xy -0.5334 -0.254)
				(xy -0.5334 -0.2794) (xy 0.5334 -0.2794) (xy 0.5334 -0.254) (xy 0.635 -0.254) (xy 0.635 0.254) (xy 0.5334 0.254)
				(xy 0.5334 0.2794)
			)
			(stroke
				(width 0)
				(type default)
			)
			(fill no)
			(layer "F.CrtYd")
		)
		(pad "1" smd rect
			(at 0.40005 0)
			(size 0.4572 0.508)
			(layers "F.Cu" "F.Mask" "F.Paste")
			(net "PSU5_PS_KILL")
		)
		(pad "2" smd rect
			(at -0.40005 0)
			(size 0.4572 0.508)
			(layers "F.Cu" "F.Mask" "F.Paste")
			(net "GND")
		)
	)
	(footprint ""
		(layer "F.Cu")
		(at 68.607686 -175.945546 90)
		(property "Reference" "C35"
			(at -4.082034 0.060706 90)
			(unlocked yes)
			(layer "F.SilkS")
			(effects
				(font
					(size 0.7874 0.5842)
					(thickness 0.1524)
				)
				(justify left)
			)
		)
		(property "Value" ""
			(at 0 0 90)
			(layer "F.Fab")
			(effects
				(font
					(size 1.27 1.27)
				)
			)
		)
		(duplicate_pad_numbers_are_jumpers no)
		(fp_line
			(start 0.7874 -0.4064)
			(end 0.7874 0.4064)
			(stroke
				(width 0.1524)
				(type default)
			)
			(layer "F.SilkS")
		)
		(fp_line
			(start -0.7874 -0.4064)
			(end 0.7874 -0.4064)
			(stroke
				(width 0.1524)
				(type default)
			)
			(layer "F.SilkS")
		)
		(fp_line
			(start 0 0.381)
			(end 0 -0.381)
			(stroke
				(width 0.1524)
				(type default)
			)
			(layer "F.SilkS")
		)
		(fp_line
			(start 0.7874 0.4064)
			(end -0.7874 0.4064)
			(stroke
				(width 0.1524)
				(type default)
			)
			(layer "F.SilkS")
		)
		(fp_line
			(start -0.7874 0.4064)
			(end -0.7874 -0.4064)
			(stroke
				(width 0.1524)
				(type default)
			)
			(layer "F.SilkS")
		)
		(fp_poly
			(pts
				(xy -0.5334 0.254) (xy -0.635 0.254) (xy -0.635 0.2286) (xy -0.635 -0.254) (xy -0.5334 -0.254) (xy -0.5334 -0.2794)
				(xy 0.5334 -0.2794) (xy 0.5334 -0.254) (xy 0.635 -0.254) (xy 0.635 0.254) (xy 0.5334 0.254) (xy 0.5334 0.2794)
				(xy -0.508 0.2794) (xy -0.5334 0.2794)
			)
			(stroke
				(width 0)
				(type default)
			)
			(fill no)
			(layer "F.CrtYd")
		)
		(pad "1" smd rect
			(at 0.40005 0 90)
			(size 0.4572 0.508)
			(layers "F.Cu" "F.Mask" "F.Paste")
			(net "P12V")
		)
		(pad "2" smd rect
			(at -0.40005 0 90)
			(size 0.4572 0.508)
			(layers "F.Cu" "F.Mask" "F.Paste")
			(net "GND")
		)
	)
	(footprint ""
		(layer "F.Cu")
		(at 26.732484 -456.748896)
		(property "Reference" "R139"
			(at -3.883914 0.13208 0)
			(unlocked yes)
			(layer "F.SilkS")
			(effects
				(font
					(size 0.7874 0.5842)
					(thickness 0.1524)
				)
				(justify left)
			)
		)
		(property "Value" ""
			(at 0 0 0)
			(layer "F.Fab")
			(effects
				(font
					(size 1.27 1.27)
				)
			)
		)
		(duplicate_pad_numbers_are_jumpers no)
		(fp_line
			(start -0.7874 -0.4064)
			(end 0.7874 -0.4064)
			(stroke
				(width 0.1524)
				(type default)
			)
			(layer "F.SilkS")
		)
		(fp_line
			(start -0.7874 0.4064)
			(end -0.7874 -0.4064)
			(stroke
				(width 0.1524)
				(type default)
			)
			(layer "F.SilkS")
		)
		(fp_line
			(start 0.7874 -0.4064)
			(end 0.7874 0.4064)
			(stroke
				(width 0.1524)
				(type default)
			)
			(layer "F.SilkS")
		)
		(fp_line
			(start 0.7874 0.4064)
			(end -0.7874 0.4064)
			(stroke
				(width 0.1524)
				(type default)
			)
			(layer "F.SilkS")
		)
		(fp_poly
			(pts
				(xy -0.508 0.2794) (xy -0.508 0.2286) (xy -0.635 0.2286) (xy -0.635 -0.254) (xy -0.5334 -0.254)
				(xy -0.5334 -0.2794) (xy 0.5334 -0.2794) (xy 0.5334 -0.254) (xy 0.635 -0.254) (xy 0.635 0.254) (xy 0.5334 0.254)
				(xy 0.5334 0.2794)
			)
			(stroke
				(width 0)
				(type default)
			)
			(fill no)
			(layer "F.CrtYd")
		)
		(pad "1" smd rect
			(at 0.40005 0)
			(size 0.4572 0.508)
			(layers "F.Cu" "F.Mask" "F.Paste")
			(net "PSU6_CSAHRE")
		)
		(pad "2" smd rect
			(at -0.40005 0)
			(size 0.4572 0.508)
			(layers "F.Cu" "F.Mask" "F.Paste")
			(net "PSU_CSAHRE")
		)
	)
	(footprint ""
		(layer "F.Cu")
		(at 91.399868 -331.16012)
		(property "Reference" "H26"
			(at -5.1308 -5.23113 0)
			(unlocked yes)
			(layer "F.SilkS")
			(effects
				(font
					(size 0.7874 0.5842)
					(thickness 0.1524)
				)
				(justify left)
			)
		)
		(property "Value" ""
			(at 0 0 0)
			(layer "F.Fab")
			(effects
				(font
					(size 1.27 1.27)
				)
			)
		)
		(duplicate_pad_numbers_are_jumpers no)
		(fp_circle
			(center 0 0)
			(end 4.826 0)
			(stroke
				(width 0.1524)
				(type default)
			)
			(fill no)
			(layer "F.SilkS")
		)
		(fp_circle
			(center 0 0)
			(end 4.826 0)
			(stroke
				(width 0.1524)
				(type default)
			)
			(fill no)
			(layer "B.SilkS")
		)
		(fp_poly
			(pts
				(arc
					(start 0 4.0132)
					(mid 0 -4.0132)
					(end 0 4.0132)
				)
			)
			(stroke
				(width 0)
				(type default)
			)
			(fill no)
			(layer "F.CrtYd")
		)
		(pad "" np_thru_hole circle
			(at 0 0)
			(size 8.001 8.001)
			(drill 8.001)
			(layers "*.Cu" "*.Mask")
			(clearance 0.381)
			(thermal_gap 0.381)
		)
		(zone
			(layers "F.Cu" "B.Cu" "In1.Cu" "In2.Cu" "In3.Cu" "In4.Cu" "In5.Cu" "In6.Cu")
			(hatch none 0.5)
			(connect_pads
				(clearance 0)
			)
			(min_thickness 0.25)
			(keepout
				(tracks not_allowed)
				(vias allowed)
				(pads allowed)
				(copperpour not_allowed)
				(footprints allowed)
			)
			(placement
				(enabled no)
				(sheetname "")
			)
			(fill
				(thermal_gap 0.5)
				(thermal_bridge_width 0.5)
				(island_removal_mode 0)
			)
			(polygon
				(pts
					(arc
						(start 91.399868 -326.63892)
						(mid 91.399868 -335.68132)
						(end 91.399868 -326.63892)
					)
				)
			)
		)
	)
	(footprint ""
		(layer "F.Cu")
		(at 26.068274 -187.950348)
		(property "Reference" "R71"
			(at -3.997198 0.128524 0)
			(unlocked yes)
			(layer "F.SilkS")
			(effects
				(font
					(size 0.7874 0.5842)
					(thickness 0.1524)
				)
				(justify left)
			)
		)
		(property "Value" ""
			(at 0 0 0)
			(layer "F.Fab")
			(effects
				(font
					(size 1.27 1.27)
				)
			)
		)
		(duplicate_pad_numbers_are_jumpers no)
		(fp_line
			(start -0.7874 -0.4064)
			(end 0.7874 -0.4064)
			(stroke
				(width 0.1524)
				(type default)
			)
			(layer "F.SilkS")
		)
		(fp_line
			(start -0.7874 0.4064)
			(end -0.7874 -0.4064)
			(stroke
				(width 0.1524)
				(type default)
			)
			(layer "F.SilkS")
		)
		(fp_line
			(start 0.7874 -0.4064)
			(end 0.7874 0.4064)
			(stroke
				(width 0.1524)
				(type default)
			)
			(layer "F.SilkS")
		)
		(fp_line
			(start 0.7874 0.4064)
			(end -0.7874 0.4064)
			(stroke
				(width 0.1524)
				(type default)
			)
			(layer "F.SilkS")
		)
		(fp_poly
			(pts
				(xy -0.508 0.2794) (xy -0.508 0.2286) (xy -0.635 0.2286) (xy -0.635 -0.254) (xy -0.5334 -0.254)
				(xy -0.5334 -0.2794) (xy 0.5334 -0.2794) (xy 0.5334 -0.254) (xy 0.635 -0.254) (xy 0.635 0.254) (xy 0.5334 0.254)
				(xy 0.5334 0.2794)
			)
			(stroke
				(width 0)
				(type default)
			)
			(fill no)
			(layer "F.CrtYd")
		)
		(pad "1" smd rect
			(at 0.40005 0)
			(size 0.4572 0.508)
			(layers "F.Cu" "F.Mask" "F.Paste")
			(net "PSU3_PS_KILL")
		)
		(pad "2" smd rect
			(at -0.40005 0)
			(size 0.4572 0.508)
			(layers "F.Cu" "F.Mask" "F.Paste")
			(net "GND")
		)
	)
	(footprint ""
		(layer "F.Cu")
		(at 68.727066 -354.308664 90)
		(property "Reference" "C63"
			(at -3.889502 0.089662 90)
			(unlocked yes)
			(layer "F.SilkS")
			(effects
				(font
					(size 0.7874 0.5842)
					(thickness 0.1524)
				)
				(justify left)
			)
		)
		(property "Value" ""
			(at 0 0 90)
			(layer "F.Fab")
			(effects
				(font
					(size 1.27 1.27)
				)
			)
		)
		(duplicate_pad_numbers_are_jumpers no)
		(fp_line
			(start 0.7874 -0.4064)
			(end 0.7874 0.4064)
			(stroke
				(width 0.1524)
				(type default)
			)
			(layer "F.SilkS")
		)
		(fp_line
			(start -0.7874 -0.4064)
			(end 0.7874 -0.4064)
			(stroke
				(width 0.1524)
				(type default)
			)
			(layer "F.SilkS")
		)
		(fp_line
			(start 0 0.381)
			(end 0 -0.381)
			(stroke
				(width 0.1524)
				(type default)
			)
			(layer "F.SilkS")
		)
		(fp_line
			(start 0.7874 0.4064)
			(end -0.7874 0.4064)
			(stroke
				(width 0.1524)
				(type default)
			)
			(layer "F.SilkS")
		)
		(fp_line
			(start -0.7874 0.4064)
			(end -0.7874 -0.4064)
			(stroke
				(width 0.1524)
				(type default)
			)
			(layer "F.SilkS")
		)
		(fp_poly
			(pts
				(xy -0.5334 0.254) (xy -0.635 0.254) (xy -0.635 0.2286) (xy -0.635 -0.254) (xy -0.5334 -0.254) (xy -0.5334 -0.2794)
				(xy 0.5334 -0.2794) (xy 0.5334 -0.254) (xy 0.635 -0.254) (xy 0.635 0.254) (xy 0.5334 0.254) (xy 0.5334 0.2794)
				(xy -0.508 0.2794) (xy -0.5334 0.2794)
			)
			(stroke
				(width 0)
				(type default)
			)
			(fill no)
			(layer "F.CrtYd")
		)
		(pad "1" smd rect
			(at 0.40005 0 90)
			(size 0.4572 0.508)
			(layers "F.Cu" "F.Mask" "F.Paste")
			(net "P12V")
		)
		(pad "2" smd rect
			(at -0.40005 0 90)
			(size 0.4572 0.508)
			(layers "F.Cu" "F.Mask" "F.Paste")
			(net "GND")
		)
	)
	(footprint ""
		(layer "F.Cu")
		(at 71.044562 -442.84646 90)
		(property "Reference" "C76"
			(at -3.873246 0.134112 90)
			(unlocked yes)
			(layer "F.SilkS")
			(effects
				(font
					(size 0.7874 0.5842)
					(thickness 0.1524)
				)
				(justify left)
			)
		)
		(property "Value" ""
			(at 0 0 90)
			(layer "F.Fab")
			(effects
				(font
					(size 1.27 1.27)
				)
			)
		)
		(duplicate_pad_numbers_are_jumpers no)
		(fp_line
			(start 0.7874 -0.4064)
			(end 0.7874 0.4064)
			(stroke
				(width 0.1524)
				(type default)
			)
			(layer "F.SilkS")
		)
		(fp_line
			(start -0.7874 -0.4064)
			(end 0.7874 -0.4064)
			(stroke
				(width 0.1524)
				(type default)
			)
			(layer "F.SilkS")
		)
		(fp_line
			(start 0 0.381)
			(end 0 -0.381)
			(stroke
				(width 0.1524)
				(type default)
			)
			(layer "F.SilkS")
		)
		(fp_line
			(start 0.7874 0.4064)
			(end -0.7874 0.4064)
			(stroke
				(width 0.1524)
				(type default)
			)
			(layer "F.SilkS")
		)
		(fp_line
			(start -0.7874 0.4064)
			(end -0.7874 -0.4064)
			(stroke
				(width 0.1524)
				(type default)
			)
			(layer "F.SilkS")
		)
		(fp_poly
			(pts
				(xy -0.5334 0.254) (xy -0.635 0.254) (xy -0.635 0.2286) (xy -0.635 -0.254) (xy -0.5334 -0.254) (xy -0.5334 -0.2794)
				(xy 0.5334 -0.2794) (xy 0.5334 -0.254) (xy 0.635 -0.254) (xy 0.635 0.254) (xy 0.5334 0.254) (xy 0.5334 0.2794)
				(xy -0.508 0.2794) (xy -0.5334 0.2794)
			)
			(stroke
				(width 0)
				(type default)
			)
			(fill no)
			(layer "F.CrtYd")
		)
		(pad "1" smd rect
			(at 0.40005 0 90)
			(size 0.4572 0.508)
			(layers "F.Cu" "F.Mask" "F.Paste")
			(net "P12V")
		)
		(pad "2" smd rect
			(at -0.40005 0 90)
			(size 0.4572 0.508)
			(layers "F.Cu" "F.Mask" "F.Paste")
			(net "GND")
		)
	)
	(footprint ""
		(layer "F.Cu")
		(at 39.936674 -464.36915 180)
		(property "Reference" "R17"
			(at -1.699514 0.166624 0)
			(unlocked yes)
			(layer "F.SilkS")
			(effects
				(font
					(size 0.7874 0.5842)
					(thickness 0.1524)
				)
				(justify left)
			)
		)
		(property "Value" ""
			(at 0 0 180)
			(layer "F.Fab")
			(effects
				(font
					(size 1.27 1.27)
				)
			)
		)
		(duplicate_pad_numbers_are_jumpers no)
		(fp_line
			(start 0.7874 0.4064)
			(end -0.7874 0.4064)
			(stroke
				(width 0.1524)
				(type default)
			)
			(layer "F.SilkS")
		)
		(fp_line
			(start 0.7874 -0.4064)
			(end 0.7874 0.4064)
			(stroke
				(width 0.1524)
				(type default)
			)
			(layer "F.SilkS")
		)
		(fp_line
			(start -0.7874 0.4064)
			(end -0.7874 -0.4064)
			(stroke
				(width 0.1524)
				(type default)
			)
			(layer "F.SilkS")
		)
		(fp_line
			(start -0.7874 -0.4064)
			(end 0.7874 -0.4064)
			(stroke
				(width 0.1524)
				(type default)
			)
			(layer "F.SilkS")
		)
		(fp_poly
			(pts
				(xy -0.508 0.2794) (xy -0.508 0.2286) (xy -0.635 0.2286) (xy -0.635 -0.254) (xy -0.5334 -0.254)
				(xy -0.5334 -0.2794) (xy 0.5334 -0.2794) (xy 0.5334 -0.254) (xy 0.635 -0.254) (xy 0.635 0.254) (xy 0.5334 0.254)
				(xy 0.5334 0.2794)
			)
			(stroke
				(width 0)
				(type default)
			)
			(fill no)
			(layer "F.CrtYd")
		)
		(pad "1" smd rect
			(at 0.40005 0 180)
			(size 0.4572 0.508)
			(layers "F.Cu" "F.Mask" "F.Paste")
			(net "PSU6_REMOTE_P")
		)
		(pad "2" smd rect
			(at -0.40005 0 180)
			(size 0.4572 0.508)
			(layers "F.Cu" "F.Mask" "F.Paste")
			(net "P12V")
		)
	)
)
